FILE_TYPE = MULTI_PHYS_TABLE;
PART 'SHUNT'
{====================================================================================================================================================================================}
:PACK_TYPE | MATERIAL | PART_NUMBER    = ENVCOMP                            | PART_NUMBER | JEDEC_TYPE  | CLASS | DESCRIPTION                 | HEIGHT     | COMPONENT_TYPE | LPID | Status |RPL| AML | Bus_Unit | Days ;
{====================================================================================================================================================================================}
'SH0201'  | 'EMPTY'  | 'N_A'(!)       = '' | 'N_A'       | 'SH0201A'   | 'IO'  | 'SHUNT 0201, ALWAYS EMPTY'  | '0.001 IN' | 'PSUEDO'       | '1864' | '???' | '???' | '???' | '' | '???' 
'SH01005' | 'EMPTY'  | 'N_A'(!)       = '' | 'N_A'       | 'SH01005A'  | 'IO'  | 'SHUNT 01005, ALWAYS EMPTY' | '0.001 IN' | 'PSUEDO'       | '2541' | '???' | '???' | '???' | '' | '???' 
END_PART
END.
